(kicad_pcb
	(version 20260206)
	(generator "pcbnew")
	(generator_version "10.0")
	(general
		(thickness 1.6)
		(legacy_teardrops no)
	)
	(paper "A4")
	(title_block
		(title "netronome-mezz — pcbd0082-001_rev01_jul9_a.brd")
		(comment 1 "Open CloudServer (Microsoft) / footprints 630-638 of 714")
	)
	(layers
		(0 "F.Cu" signal "TOP")
		(4 "In1.Cu" signal "02_GND")
		(6 "In2.Cu" signal "03_SIG")
		(8 "In3.Cu" signal "04_SIG")
		(10 "In4.Cu" signal "05_GND")
		(12 "In5.Cu" signal "06_PWR1")
		(14 "In6.Cu" signal "07_SIG")
		(16 "In7.Cu" signal "08_SIG")
		(18 "In8.Cu" signal "09_GND")
		(2 "B.Cu" signal "BOTTOM")
		(9 "F.Adhes" user "F.Adhesive")
		(11 "B.Adhes" user "B.Adhesive")
		(13 "F.Paste" user "Package Geometry/Pastemask Top")
		(15 "B.Paste" user "Package Geometry/Pastemask Bottom")
		(5 "F.SilkS" user "Ref Des/Silkscreen Top")
		(7 "B.SilkS" user "Ref Des/Silkscreen Bottom")
		(1 "F.Mask" user "Board Geometry/Soldermask Top")
		(3 "B.Mask" user "Board Geometry/Soldermask Bottom")
		(17 "Dwgs.User" user "User.Drawings")
		(19 "Cmts.User" user "User.Comments")
		(21 "Eco1.User" user "User.Eco1")
		(23 "Eco2.User" user "User.Eco2")
		(25 "Edge.Cuts" user "Board Geometry/Outline")
		(27 "Margin" user)
		(31 "F.CrtYd" user "Package Geometry/Place Bound Top")
		(29 "B.CrtYd" user "Package Geometry/Place Bound Bottom")
		(35 "F.Fab" user "Ref Des/Assembly Top")
		(33 "B.Fab" user "Ref Des/Assembly Bottom")
		(45 "User.4" user "COMPVAL_TYPE_BOTTOM")
	)
	(footprint ""
		(layer "B.Cu")
		(at 75.451005 19.055994)
		(property "Reference" "V_A-DQ20"
			(at 0 0 0)
			(layer "B.SilkS")
			(hide yes)
			(effects
				(font
					(size 1.27 1.27)
				)
				(justify mirror)
			)
		)
		(property "Value" ""
			(at 0 0 0)
			(layer "B.Fab")
			(effects
				(font
					(size 1.27 1.27)
				)
				(justify mirror)
			)
		)
		(duplicate_pad_numbers_are_jumpers no)
		(pad "1" thru_hole circle
			(at 0 0 180)
			(size 0.4572 0.4572)
			(drill 0.20574)
			(layers "*.Cu" "*.Mask")
			(remove_unused_layers no)
			(net "DDR0_32A_DQ20")
			(clearance 0.1143)
			(thermal_gap 0.1143)
		)
	)
	(footprint ""
		(layer "B.Cu")
		(at 58.236993 7.542022 180)
		(property "Reference" "C90"
			(at 0.097663 2.335022 270)
			(unlocked yes)
			(layer "B.SilkS")
			(effects
				(font
					(size 0.7874 0.5842)
					(thickness 0.127)
				)
				(justify mirror)
			)
		)
		(property "Value" ""
			(at 0 0 0)
			(layer "B.Fab")
			(effects
				(font
					(size 1.27 1.27)
				)
				(justify mirror)
			)
		)
		(duplicate_pad_numbers_are_jumpers no)
		(fp_circle
			(center 0 0)
			(end -0.104648 0)
			(stroke
				(width 0.1016)
				(type default)
			)
			(fill no)
			(layer "B.SilkS")
		)
		(fp_poly
			(pts
				(xy 0.381 -0.889) (xy 0.381 0.889) (xy -0.381 0.889) (xy -0.381 -0.889)
			)
			(stroke
				(width 0)
				(type default)
			)
			(fill no)
			(layer "B.CrtYd")
		)
		(fp_line
			(start 0.508 1.016)
			(end 0.508 -1.016)
			(stroke
				(width 0.0254)
				(type default)
			)
			(layer "B.Fab")
		)
		(fp_line
			(start 0.508 -1.016)
			(end 0.254 -1.016)
			(stroke
				(width 0.0254)
				(type default)
			)
			(layer "B.Fab")
		)
		(fp_line
			(start 0.254 -1.016)
			(end -0.508 -1.016)
			(stroke
				(width 0.0254)
				(type default)
			)
			(layer "B.Fab")
		)
		(fp_line
			(start -0.508 1.016)
			(end 0.508 1.016)
			(stroke
				(width 0.0254)
				(type default)
			)
			(layer "B.Fab")
		)
		(fp_line
			(start -0.508 -1.016)
			(end -0.508 1.016)
			(stroke
				(width 0.0254)
				(type default)
			)
			(layer "B.Fab")
		)
		(pad "1" smd custom
			(at 0 -0.500126)
			(size 0.127 0.127)
			(layers "B.Cu" "B.Mask" "B.Paste")
			(net "VDDA_PCIE0")
			(options
				(clearance outline)
				(anchor circle)
			)
			(primitives
				(gr_poly
					(pts
						(xy -0.1778 0.254) (xy 0.1778 0.254) (xy 0.254 0.1778) (xy 0.254 -0.1778) (xy 0.1778 -0.254) (xy -0.1778 -0.254)
						(xy -0.254 -0.1778) (xy -0.254 0.1778)
					)
					(width 0)
					(fill yes)
				)
			)
		)
		(pad "2" smd custom
			(at 0 0.500126)
			(size 0.127 0.127)
			(layers "B.Cu" "B.Mask" "B.Paste")
			(net "GND")
			(options
				(clearance outline)
				(anchor circle)
			)
			(primitives
				(gr_poly
					(pts
						(xy -0.1778 0.254) (xy 0.1778 0.254) (xy 0.254 0.1778) (xy 0.254 -0.1778) (xy 0.1778 -0.254) (xy -0.1778 -0.254)
						(xy -0.254 -0.1778) (xy -0.254 0.1778)
					)
					(width 0)
					(fill yes)
				)
			)
		)
	)
	(footprint ""
		(layer "B.Cu")
		(at 59.7916 35.56 90)
		(property "Reference" "C12"
			(at 0.98933 0.5334 0)
			(unlocked yes)
			(layer "B.SilkS")
			(effects
				(font
					(size 0.7874 0.5842)
					(thickness 0.127)
				)
				(justify left mirror)
			)
		)
		(property "Value" "22UF"
			(at 0.148158 1.7526 0)
			(unlocked yes)
			(layer "B.Fab")
			(hide yes)
			(effects
				(font
					(size 1.27 0.9652)
					(thickness 0.000001)
				)
				(justify left mirror)
			)
		)
		(property "Device Type" "CAPC0063"
			(at 0.148158 1.7526 0)
			(unlocked yes)
			(layer "B.Fab")
			(hide yes)
			(effects
				(font
					(size 1.27 0.9652)
					(thickness 0.000001)
				)
				(justify left mirror)
			)
		)
		(duplicate_pad_numbers_are_jumpers no)
		(fp_circle
			(center 0 0)
			(end 0 0.127)
			(stroke
				(width 0.2032)
				(type default)
			)
			(fill no)
			(layer "B.SilkS")
		)
		(fp_poly
			(pts
				(xy -0.7874 -1.6637) (xy 0.7874 -1.6637) (xy 0.7874 1.6637) (xy -0.7874 1.6637)
			)
			(stroke
				(width 0)
				(type default)
			)
			(fill no)
			(layer "B.CrtYd")
		)
		(fp_line
			(start 0.4064 -0.7874)
			(end -0.4064 -0.7874)
			(stroke
				(width 0.0254)
				(type default)
			)
			(layer "B.Fab")
		)
		(fp_line
			(start -0.4064 -0.7874)
			(end -0.4064 0.8128)
			(stroke
				(width 0.0254)
				(type default)
			)
			(layer "B.Fab")
		)
		(fp_line
			(start 0.4064 0.8128)
			(end 0.4064 -0.7874)
			(stroke
				(width 0.0254)
				(type default)
			)
			(layer "B.Fab")
		)
		(fp_line
			(start -0.4064 0.8128)
			(end 0.4064 0.8128)
			(stroke
				(width 0.0254)
				(type default)
			)
			(layer "B.Fab")
		)
		(pad "1" smd rect
			(at 0 -0.8001 270)
			(size 0.8636 0.9652)
			(layers "B.Cu" "B.Mask" "B.Paste")
			(net "VDD_CORE")
		)
		(pad "2" smd rect
			(at 0 0.8001 270)
			(size 0.8636 0.9652)
			(layers "B.Cu" "B.Mask" "B.Paste")
			(net "GND")
		)
		(zone
			(layer "B.Cu")
			(hatch none 0.5)
			(connect_pads
				(clearance 0)
			)
			(min_thickness 0.25)
			(keepout
				(tracks not_allowed)
				(vias allowed)
				(pads allowed)
				(copperpour not_allowed)
				(footprints allowed)
			)
			(placement
				(enabled no)
				(sheetname "")
			)
			(fill
				(thermal_gap 0.5)
				(thermal_bridge_width 0.5)
				(island_removal_mode 0)
			)
			(polygon
				(pts
					(xy 59.5376 35.4965) (xy 59.5376 35.6235) (xy 60.0456 35.6235) (xy 60.0456 35.4965)
				)
			)
		)
	)
	(footprint ""
		(layer "B.Cu")
		(at 83.185 44.323 180)
		(property "Reference" "C205"
			(at -0.98933 -3.429 270)
			(unlocked yes)
			(layer "B.SilkS")
			(effects
				(font
					(size 0.7874 0.5842)
					(thickness 0.127)
				)
				(justify left mirror)
			)
		)
		(property "Value" "1UF"
			(at 0.091846 0.2921 90)
			(unlocked yes)
			(layer "B.Fab")
			(hide yes)
			(effects
				(font
					(size 0.7874 0.5842)
					(thickness 0.2032)
				)
				(justify left mirror)
			)
		)
		(property "Device Type" "CAPC0028"
			(at 0.091846 0.2921 90)
			(unlocked yes)
			(layer "B.Fab")
			(hide yes)
			(effects
				(font
					(size 0.7874 0.5842)
					(thickness 0.2032)
				)
				(justify left mirror)
			)
		)
		(duplicate_pad_numbers_are_jumpers no)
		(fp_poly
			(pts
				(xy -0.635 1.0668) (xy -0.635 -1.0668) (xy 0.635 -1.0668) (xy 0.635 1.0668)
			)
			(stroke
				(width 0)
				(type default)
			)
			(fill no)
			(layer "B.CrtYd")
		)
		(fp_line
			(start 0.254 0.508)
			(end 0.254 -0.508)
			(stroke
				(width 0.0254)
				(type default)
			)
			(layer "B.Fab")
		)
		(fp_line
			(start 0.254 -0.508)
			(end -0.254 -0.508)
			(stroke
				(width 0.0254)
				(type default)
			)
			(layer "B.Fab")
		)
		(fp_line
			(start -0.254 0.508)
			(end 0.254 0.508)
			(stroke
				(width 0.0254)
				(type default)
			)
			(layer "B.Fab")
		)
		(fp_line
			(start -0.254 -0.508)
			(end -0.254 0.508)
			(stroke
				(width 0.0254)
				(type default)
			)
			(layer "B.Fab")
		)
		(pad "1" smd rect
			(at 0 -0.4191)
			(size 0.508 0.5334)
			(layers "B.Cu" "B.Mask" "B.Paste")
			(net "11N2159")
		)
		(pad "2" smd rect
			(at 0 0.4191)
			(size 0.508 0.5334)
			(layers "B.Cu" "B.Mask" "B.Paste")
			(net "GND")
		)
		(zone
			(layer "B.Cu")
			(hatch none 0.5)
			(connect_pads
				(clearance 0)
			)
			(min_thickness 0.25)
			(keepout
				(tracks not_allowed)
				(vias allowed)
				(pads allowed)
				(copperpour not_allowed)
				(footprints allowed)
			)
			(placement
				(enabled no)
				(sheetname "")
			)
			(fill
				(thermal_gap 0.5)
				(thermal_bridge_width 0.5)
				(island_removal_mode 0)
			)
			(polygon
				(pts
					(xy 83.2104 44.3484) (xy 83.2104 44.2976) (xy 83.1596 44.2976) (xy 83.1596 44.3484)
				)
			)
		)
	)
	(footprint ""
		(layer "B.Cu")
		(at 52.737004 6.042025 90)
		(property "Reference" "C42"
			(at 0 0 90)
			(layer "B.SilkS")
			(hide yes)
			(effects
				(font
					(size 1.27 1.27)
				)
				(justify mirror)
			)
		)
		(property "Value" ""
			(at 0 0 90)
			(layer "B.Fab")
			(effects
				(font
					(size 1.27 1.27)
				)
				(justify mirror)
			)
		)
		(duplicate_pad_numbers_are_jumpers no)
		(fp_circle
			(center 0 0)
			(end 0 0.104648)
			(stroke
				(width 0.1016)
				(type default)
			)
			(fill no)
			(layer "B.SilkS")
		)
		(fp_poly
			(pts
				(xy 0.381 -0.889) (xy 0.381 0.889) (xy -0.381 0.889) (xy -0.381 -0.889)
			)
			(stroke
				(width 0)
				(type default)
			)
			(fill no)
			(layer "B.CrtYd")
		)
		(fp_line
			(start 0.508 -1.016)
			(end 0.254 -1.016)
			(stroke
				(width 0.0254)
				(type default)
			)
			(layer "B.Fab")
		)
		(fp_line
			(start 0.254 -1.016)
			(end -0.508 -1.016)
			(stroke
				(width 0.0254)
				(type default)
			)
			(layer "B.Fab")
		)
		(fp_line
			(start -0.508 -1.016)
			(end -0.508 1.016)
			(stroke
				(width 0.0254)
				(type default)
			)
			(layer "B.Fab")
		)
		(fp_line
			(start 0.508 1.016)
			(end 0.508 -1.016)
			(stroke
				(width 0.0254)
				(type default)
			)
			(layer "B.Fab")
		)
		(fp_line
			(start -0.508 1.016)
			(end 0.508 1.016)
			(stroke
				(width 0.0254)
				(type default)
			)
			(layer "B.Fab")
		)
		(pad "1" smd custom
			(at 0 -0.500126 270)
			(size 0.127 0.127)
			(layers "B.Cu" "B.Mask" "B.Paste")
			(net "VDDAH_SERDES")
			(options
				(clearance outline)
				(anchor circle)
			)
			(primitives
				(gr_poly
					(pts
						(xy -0.1778 0.254) (xy 0.1778 0.254) (xy 0.254 0.1778) (xy 0.254 -0.1778) (xy 0.1778 -0.254) (xy -0.1778 -0.254)
						(xy -0.254 -0.1778) (xy -0.254 0.1778)
					)
					(width 0)
					(fill yes)
				)
			)
		)
		(pad "2" smd custom
			(at 0 0.500126 270)
			(size 0.127 0.127)
			(layers "B.Cu" "B.Mask" "B.Paste")
			(net "GND")
			(options
				(clearance outline)
				(anchor circle)
			)
			(primitives
				(gr_poly
					(pts
						(xy -0.1778 0.254) (xy 0.1778 0.254) (xy 0.254 0.1778) (xy 0.254 -0.1778) (xy 0.1778 -0.254) (xy -0.1778 -0.254)
						(xy -0.254 -0.1778) (xy -0.254 0.1778)
					)
					(width 0)
					(fill yes)
				)
			)
		)
	)
	(footprint ""
		(layer "B.Cu")
		(at 64.262 25.908 180)
		(property "Reference" "C67"
			(at -1.37033 -2.159 270)
			(unlocked yes)
			(layer "B.SilkS")
			(effects
				(font
					(size 0.7874 0.5842)
					(thickness 0.127)
				)
				(justify left mirror)
			)
		)
		(property "Value" "100UF"
			(at 0.78232 0.4826 90)
			(unlocked yes)
			(layer "B.Fab")
			(hide yes)
			(effects
				(font
					(size 1.27 0.9652)
					(thickness 0.000001)
				)
				(justify left mirror)
			)
		)
		(property "Device Type" "CAPC0087"
			(at 0.78232 0.4826 90)
			(unlocked yes)
			(layer "B.Fab")
			(hide yes)
			(effects
				(font
					(size 1.27 0.9652)
					(thickness 0.000001)
				)
				(justify left mirror)
			)
		)
		(duplicate_pad_numbers_are_jumpers no)
		(fp_circle
			(center 0 0)
			(end -0.508 0)
			(stroke
				(width 0.2032)
				(type default)
			)
			(fill no)
			(layer "B.SilkS")
		)
		(fp_poly
			(pts
				(xy 1.007212 2.9464) (xy -1.27 2.9464) (xy -1.27 -2.9464) (xy 1.007212 -2.9464)
			)
			(stroke
				(width 0)
				(type default)
			)
			(fill no)
			(layer "B.CrtYd")
		)
		(fp_line
			(start 1.016 2.794)
			(end 1.016 -2.794)
			(stroke
				(width 0.0254)
				(type default)
			)
			(layer "B.Fab")
		)
		(fp_line
			(start 1.016 -2.794)
			(end -1.016 -2.794)
			(stroke
				(width 0.0254)
				(type default)
			)
			(layer "B.Fab")
		)
		(fp_line
			(start -1.016 2.794)
			(end 1.016 2.794)
			(stroke
				(width 0.0254)
				(type default)
			)
			(layer "B.Fab")
		)
		(fp_line
			(start -1.016 -2.794)
			(end -1.016 2.794)
			(stroke
				(width 0.0254)
				(type default)
			)
			(layer "B.Fab")
		)
		(pad "1" smd rect
			(at 0 -1.6764)
			(size 1.524 1.524)
			(layers "B.Cu" "B.Mask" "B.Paste")
			(net "DDR_VDDQ")
		)
		(pad "2" smd rect
			(at 0 1.6764)
			(size 1.524 1.524)
			(layers "B.Cu" "B.Mask" "B.Paste")
			(net "GND")
		)
		(zone
			(layer "B.Cu")
			(hatch none 0.5)
			(connect_pads
				(clearance 0)
			)
			(min_thickness 0.25)
			(keepout
				(tracks allowed)
				(vias not_allowed)
				(pads allowed)
				(copperpour not_allowed)
				(footprints allowed)
			)
			(placement
				(enabled no)
				(sheetname "")
			)
			(fill
				(thermal_gap 0.5)
				(thermal_bridge_width 0.5)
				(island_removal_mode 0)
			)
			(polygon
				(pts
					(xy 63.4746 24.3078) (xy 65.0494 24.3078) (xy 65.0494 27.5082) (xy 63.4746 27.5082)
				)
			)
		)
		(zone
			(layer "B.Cu")
			(hatch none 0.5)
			(connect_pads
				(clearance 0)
			)
			(min_thickness 0.25)
			(keepout
				(tracks not_allowed)
				(vias allowed)
				(pads allowed)
				(copperpour not_allowed)
				(footprints allowed)
			)
			(placement
				(enabled no)
				(sheetname "")
			)
			(fill
				(thermal_gap 0.5)
				(thermal_bridge_width 0.5)
				(island_removal_mode 0)
			)
			(polygon
				(pts
					(xy 63.4746 25.1714) (xy 65.0494 25.1714) (xy 65.0494 25.019) (xy 63.4746 25.019)
				)
			)
		)
		(zone
			(layer "B.Cu")
			(hatch none 0.5)
			(connect_pads
				(clearance 0)
			)
			(min_thickness 0.25)
			(keepout
				(tracks not_allowed)
				(vias allowed)
				(pads allowed)
				(copperpour not_allowed)
				(footprints allowed)
			)
			(placement
				(enabled no)
				(sheetname "")
			)
			(fill
				(thermal_gap 0.5)
				(thermal_bridge_width 0.5)
				(island_removal_mode 0)
			)
			(polygon
				(pts
					(xy 63.4746 26.797) (xy 65.0494 26.797) (xy 65.0494 26.6446) (xy 63.4746 26.6446)
				)
			)
		)
	)
	(footprint ""
		(layer "B.Cu")
		(at 82.65099 1.899006)
		(property "Reference" "V1_A-A05"
			(at 0 0 0)
			(layer "B.SilkS")
			(hide yes)
			(effects
				(font
					(size 1.27 1.27)
				)
				(justify mirror)
			)
		)
		(property "Value" ""
			(at 0 0 0)
			(layer "B.Fab")
			(effects
				(font
					(size 1.27 1.27)
				)
				(justify mirror)
			)
		)
		(duplicate_pad_numbers_are_jumpers no)
		(pad "1" thru_hole circle
			(at 0 0 180)
			(size 0.4572 0.4572)
			(drill 0.20574)
			(layers "*.Cu" "*.Mask")
			(remove_unused_layers no)
			(net "DDR0_32A_A5")
			(clearance 0.1143)
			(thermal_gap 0.1143)
		)
	)
	(footprint ""
		(layer "B.Cu")
		(at 23.241 16.891)
		(property "Reference" "R29"
			(at 0.86233 0.254 270)
			(unlocked yes)
			(layer "B.SilkS")
			(effects
				(font
					(size 0.7874 0.5842)
					(thickness 0.127)
				)
				(justify left mirror)
			)
		)
		(property "Value" "4.75K"
			(at 0.148158 1.3462 270)
			(unlocked yes)
			(layer "B.Fab")
			(hide yes)
			(effects
				(font
					(size 1.27 0.9652)
					(thickness 0.000001)
				)
				(justify left mirror)
			)
		)
		(property "Device Type" "REST4024"
			(at 0.148158 1.3462 270)
			(unlocked yes)
			(layer "B.Fab")
			(hide yes)
			(effects
				(font
					(size 1.27 0.9652)
					(thickness 0.000001)
				)
				(justify left mirror)
			)
		)
		(duplicate_pad_numbers_are_jumpers no)
		(fp_poly
			(pts
				(xy -0.635 1.0668) (xy -0.635 -1.0668) (xy 0.635 -1.0668) (xy 0.635 1.0668)
			)
			(stroke
				(width 0)
				(type default)
			)
			(fill no)
			(layer "B.CrtYd")
		)
		(fp_line
			(start -0.254 -0.508)
			(end -0.254 0.508)
			(stroke
				(width 0.0254)
				(type default)
			)
			(layer "B.Fab")
		)
		(fp_line
			(start -0.254 0.508)
			(end 0.254 0.508)
			(stroke
				(width 0.0254)
				(type default)
			)
			(layer "B.Fab")
		)
		(fp_line
			(start 0.254 -0.508)
			(end -0.254 -0.508)
			(stroke
				(width 0.0254)
				(type default)
			)
			(layer "B.Fab")
		)
		(fp_line
			(start 0.254 0.508)
			(end 0.254 -0.508)
			(stroke
				(width 0.0254)
				(type default)
			)
			(layer "B.Fab")
		)
		(pad "1" smd rect
			(at 0 -0.4191 180)
			(size 0.508 0.5334)
			(layers "B.Cu" "B.Mask" "B.Paste")
			(net "VDD_3.3V")
		)
		(pad "2" smd rect
			(at 0 0.4191 180)
			(size 0.508 0.5334)
			(layers "B.Cu" "B.Mask" "B.Paste")
			(net "NFP_ARM_SPI_FLASH_WP_L")
		)
		(zone
			(layer "B.Cu")
			(hatch none 0.5)
			(connect_pads
				(clearance 0)
			)
			(min_thickness 0.25)
			(keepout
				(tracks not_allowed)
				(vias allowed)
				(pads allowed)
				(copperpour not_allowed)
				(footprints allowed)
			)
			(placement
				(enabled no)
				(sheetname "")
			)
			(fill
				(thermal_gap 0.5)
				(thermal_bridge_width 0.5)
				(island_removal_mode 0)
			)
			(polygon
				(pts
					(xy 23.2156 16.8656) (xy 23.2156 16.9164) (xy 23.2664 16.9164) (xy 23.2664 16.8656)
				)
			)
		)
	)
	(footprint ""
		(layer "B.Cu")
		(at 60.325 0.762 180)
		(property "Reference" "C155"
			(at 0.145212 0.8763 270)
			(unlocked yes)
			(layer "B.SilkS")
			(effects
				(font
					(size 0.7874 0.5842)
					(thickness 0.127)
				)
				(justify left mirror)
			)
		)
		(property "Value" "0.22UF"
			(at 0.091846 0.2921 90)
			(unlocked yes)
			(layer "B.Fab")
			(hide yes)
			(effects
				(font
					(size 0.7874 0.5842)
					(thickness 0.2032)
				)
				(justify left mirror)
			)
		)
		(property "Device Type" "CAPC0062"
			(at 0.091846 0.2921 90)
			(unlocked yes)
			(layer "B.Fab")
			(hide yes)
			(effects
				(font
					(size 0.7874 0.5842)
					(thickness 0.2032)
				)
				(justify left mirror)
			)
		)
		(duplicate_pad_numbers_are_jumpers no)
		(fp_poly
			(pts
				(xy -0.635 1.0668) (xy -0.635 -1.0668) (xy 0.635 -1.0668) (xy 0.635 1.0668)
			)
			(stroke
				(width 0)
				(type default)
			)
			(fill no)
			(layer "B.CrtYd")
		)
		(fp_line
			(start 0.254 0.508)
			(end 0.254 -0.508)
			(stroke
				(width 0.0254)
				(type default)
			)
			(layer "B.Fab")
		)
		(fp_line
			(start 0.254 -0.508)
			(end -0.254 -0.508)
			(stroke
				(width 0.0254)
				(type default)
			)
			(layer "B.Fab")
		)
		(fp_line
			(start -0.254 0.508)
			(end 0.254 0.508)
			(stroke
				(width 0.0254)
				(type default)
			)
			(layer "B.Fab")
		)
		(fp_line
			(start -0.254 -0.508)
			(end -0.254 0.508)
			(stroke
				(width 0.0254)
				(type default)
			)
			(layer "B.Fab")
		)
		(pad "1" smd rect
			(at 0 -0.4191)
			(size 0.508 0.5334)
			(layers "B.Cu" "B.Mask" "B.Paste")
			(net "_NFP_PCIE0_PER1_P")
		)
		(pad "2" smd rect
			(at 0 0.4191)
			(size 0.508 0.5334)
			(layers "B.Cu" "B.Mask" "B.Paste")
			(net "NFP_PCIE0_PER1_P")
		)
		(zone
			(layer "B.Cu")
			(hatch none 0.5)
			(connect_pads
				(clearance 0)
			)
			(min_thickness 0.25)
			(keepout
				(tracks not_allowed)
				(vias allowed)
				(pads allowed)
				(copperpour not_allowed)
				(footprints allowed)
			)
			(placement
				(enabled no)
				(sheetname "")
			)
			(fill
				(thermal_gap 0.5)
				(thermal_bridge_width 0.5)
				(island_removal_mode 0)
			)
			(polygon
				(pts
					(xy 60.3504 0.7874) (xy 60.3504 0.7366) (xy 60.2996 0.7366) (xy 60.2996 0.7874)
				)
			)
		)
	)
)
